# T6G (Grand Teton) — schematic netlist excerpt (pin names and nets, part order shuffled) for the footprints in the layout excerpt that follows; sources: Cadence DE-HDL packaged netlist, KiCad conversion of 04192023_DAF0TMB3IC0_F0TG_MB_C_brd_V02_OCP.brd

C2431  Q_CAP  22UF 4V 20% X6S  pkg C0402  page 74 : A = PVDDCR_SOC_P1 ; B = GND
PC108  Q_CAPP  220UF 4V 20% SPCAP  pkg SMLF  page 194 : A = PVDDCR_CPU0_P0 ; B = GND

(kicad_pcb
	(version 20260206)
	(generator "pcbnew")
	(generator_version "10.0")
	(general
		(thickness 1.6)
		(legacy_teardrops no)
	)
	(paper "A4")
	(title_block
		(title "04192023_DAF0TMB3IC0_F0TG_MB_C_brd_V02_OCP.brd")
		(comment 1 "Grand Teton / footprints 6919-6920 of 8354")
	)
	(layers
		(0 "F.Cu" signal "TOP")
		(4 "In1.Cu" signal "GND")
		(6 "In2.Cu" signal "IN1")
		(8 "In3.Cu" signal "GND1")
		(10 "In4.Cu" signal "IN2")
		(12 "In5.Cu" signal "GND2")
		(14 "In6.Cu" signal "IN3")
		(16 "In7.Cu" signal "GND3")
		(18 "In8.Cu" signal "VCC")
		(20 "In9.Cu" signal "VCC1")
		(22 "In10.Cu" signal "GND4")
		(24 "In11.Cu" signal "IN4")
		(26 "In12.Cu" signal "GND5")
		(28 "In13.Cu" signal "IN5")
		(30 "In14.Cu" signal "GND6")
		(32 "In15.Cu" signal "IN6")
		(34 "In16.Cu" signal "GND7")
		(2 "B.Cu" signal "BOTTOM")
		(9 "F.Adhes" user "F.Adhesive")
		(11 "B.Adhes" user "B.Adhesive")
		(13 "F.Paste" user "Package Geometry/Pastemask Top")
		(15 "B.Paste" user "Package Geometry/Pastemask Bottom")
		(5 "F.SilkS" user "Ref Des/Silkscreen Top")
		(7 "B.SilkS" user "Ref Des/Silkscreen Bottom")
		(1 "F.Mask" user "Board Geometry/Soldermask Top")
		(3 "B.Mask" user "Board Geometry/Soldermask Bottom")
		(17 "Dwgs.User" user "User.Drawings")
		(19 "Cmts.User" user "User.Comments")
		(21 "Eco1.User" user "User.Eco1")
		(23 "Eco2.User" user "User.Eco2")
		(25 "Edge.Cuts" user "Board Geometry/Outline")
		(27 "Margin" user)
		(31 "F.CrtYd" user "Package Geometry/Place Bound Top")
		(29 "B.CrtYd" user "Package Geometry/Place Bound Bottom")
		(35 "F.Fab" user "Ref Des/Assembly Top")
		(33 "B.Fab" user "Ref Des/Assembly Bottom")
	)
	(footprint ""
		(layer "B.Cu")
		(at 380.149354 -189.461648 90)
		(property "Reference" "PC108"
			(at 6.027928 1.101598 270)
			(unlocked yes)
			(layer "B.SilkS")
			(effects
				(font
					(size 0.7874 0.5842)
					(thickness 0.1524)
				)
				(justify left mirror)
			)
		)
		(property "Value" ""
			(at 0 0 90)
			(layer "B.Fab")
			(effects
				(font
					(size 1.27 1.27)
				)
				(justify mirror)
			)
		)
		(duplicate_pad_numbers_are_jumpers no)
		(fp_line
			(start 4.533392 -2.249932)
			(end -4.533392 -2.249932)
			(stroke
				(width 0.1524)
				(type default)
			)
			(layer "B.SilkS")
		)
		(fp_line
			(start -4.533392 -2.249932)
			(end -4.533392 2.249932)
			(stroke
				(width 0.1524)
				(type default)
			)
			(layer "B.SilkS")
		)
		(fp_line
			(start 4.533392 2.249932)
			(end 4.533392 -2.249932)
			(stroke
				(width 0.1524)
				(type default)
			)
			(layer "B.SilkS")
		)
		(fp_line
			(start -4.533392 2.249932)
			(end 4.533392 2.249932)
			(stroke
				(width 0.1524)
				(type default)
			)
			(layer "B.SilkS")
		)
		(fp_rect
			(start 4.533392 -2.326132)
			(end 5.39242 2.326132)
			(stroke
				(width 0)
				(type default)
			)
			(fill yes)
			(layer "B.SilkS")
		)
		(fp_line
			(start 3.750056 -2.249932)
			(end -3.750056 -2.249932)
			(stroke
				(width 0.1)
				(type default)
			)
			(layer "B.Fab")
		)
		(fp_line
			(start -3.750056 -2.249932)
			(end -3.750056 2.249932)
			(stroke
				(width 0.1)
				(type default)
			)
			(layer "B.Fab")
		)
		(fp_line
			(start 3.750056 2.249932)
			(end 3.750056 -2.249932)
			(stroke
				(width 0.1)
				(type default)
			)
			(layer "B.Fab")
		)
		(fp_line
			(start -3.750056 2.249932)
			(end 3.750056 2.249932)
			(stroke
				(width 0.1)
				(type default)
			)
			(layer "B.Fab")
		)
		(fp_text user "+"
			(at 6.322314 0.786384 0)
			(unlocked yes)
			(layer "B.SilkS")
			(effects
				(font
					(size 1.905 1.4224)
					(thickness 0.1524)
				)
				(justify left mirror)
			)
		)
		(fp_text user "-"
			(at -4.728718 1.129792 90)
			(unlocked yes)
			(layer "B.SilkS")
			(effects
				(font
					(size 1.905 1.4224)
					(thickness 0.1524)
				)
				(justify left mirror)
			)
		)
		(fp_text user "-"
			(at -4.8514 -0.14605 90)
			(unlocked yes)
			(layer "B.Fab")
			(effects
				(font
					(size 1.905 1.4224)
					(thickness 0.1524)
				)
				(justify left mirror)
			)
		)
		(fp_text user "+"
			(at 6.322314 0.786384 0)
			(unlocked yes)
			(layer "B.Fab")
			(effects
				(font
					(size 1.905 1.4224)
					(thickness 0.1524)
				)
				(justify left mirror)
			)
		)
		(pad "1" smd rect
			(at 3.199892 0 270)
			(size 2.413 2.8194)
			(layers "B.Cu" "B.Mask" "B.Paste")
			(net "PVDDCR_CPU0_P0")
		)
		(pad "2" smd rect
			(at -3.199892 0 270)
			(size 2.413 2.8194)
			(layers "B.Cu" "B.Mask" "B.Paste")
			(net "GND")
		)
	)
	(footprint ""
		(layer "B.Cu")
		(at 110.525814 -256.012442 -90)
		(property "Reference" "C2431"
			(at 0 0 90)
			(layer "B.SilkS")
			(hide yes)
			(effects
				(font
					(size 1.27 1.27)
				)
				(justify mirror)
			)
		)
		(property "Value" ""
			(at 0 0 90)
			(layer "B.Fab")
			(effects
				(font
					(size 1.27 1.27)
				)
				(justify mirror)
			)
		)
		(duplicate_pad_numbers_are_jumpers no)
		(fp_line
			(start -0.7874 0.4064)
			(end 0.7874 0.4064)
			(stroke
				(width 0.1524)
				(type default)
			)
			(layer "B.SilkS")
		)
		(fp_line
			(start 0.7874 0.4064)
			(end 0.7874 -0.4064)
			(stroke
				(width 0.1524)
				(type default)
			)
			(layer "B.SilkS")
		)
		(fp_line
			(start -0.7874 -0.4064)
			(end -0.7874 0.4064)
			(stroke
				(width 0.1524)
				(type default)
			)
			(layer "B.SilkS")
		)
		(fp_line
			(start 0.7874 -0.4064)
			(end -0.7874 -0.4064)
			(stroke
				(width 0.1524)
				(type default)
			)
			(layer "B.SilkS")
		)
		(fp_line
			(start -0.67945 0.3048)
			(end -0.120396 0.3048)
			(stroke
				(width 0.1)
				(type default)
			)
			(layer "B.Fab")
		)
		(fp_line
			(start -0.120396 0.3048)
			(end -0.120396 0.2794)
			(stroke
				(width 0.1)
				(type default)
			)
			(layer "B.Fab")
		)
		(fp_line
			(start 0.12065 0.3048)
			(end 0.67945 0.3048)
			(stroke
				(width 0.1)
				(type default)
			)
			(layer "B.Fab")
		)
		(fp_line
			(start 0.67945 0.3048)
			(end 0.67945 -0.305054)
			(stroke
				(width 0.1)
				(type default)
			)
			(layer "B.Fab")
		)
		(fp_line
			(start -0.120396 0.2794)
			(end 0.12065 0.2794)
			(stroke
				(width 0.1)
				(type default)
			)
			(layer "B.Fab")
		)
		(fp_line
			(start 0.12065 0.2794)
			(end 0.12065 0.3048)
			(stroke
				(width 0.1)
				(type default)
			)
			(layer "B.Fab")
		)
		(fp_line
			(start -0.12065 -0.2794)
			(end -0.12065 -0.3048)
			(stroke
				(width 0.1)
				(type default)
			)
			(layer "B.Fab")
		)
		(fp_line
			(start 0.12065 -0.2794)
			(end -0.12065 -0.2794)
			(stroke
				(width 0.1)
				(type default)
			)
			(layer "B.Fab")
		)
		(fp_line
			(start -0.67945 -0.3048)
			(end -0.67945 0.3048)
			(stroke
				(width 0.1)
				(type default)
			)
			(layer "B.Fab")
		)
		(fp_line
			(start -0.12065 -0.3048)
			(end -0.67945 -0.3048)
			(stroke
				(width 0.1)
				(type default)
			)
			(layer "B.Fab")
		)
		(fp_line
			(start 0.12065 -0.305054)
			(end 0.12065 -0.2794)
			(stroke
				(width 0.1)
				(type default)
			)
			(layer "B.Fab")
		)
		(fp_line
			(start 0.67945 -0.305054)
			(end 0.12065 -0.305054)
			(stroke
				(width 0.1)
				(type default)
			)
			(layer "B.Fab")
		)
		(pad "1" smd circle
			(at 0.40005 0 90)
			(size 0 0)
			(layers "B.Cu" "B.Mask" "B.Paste")
			(net "PVDDCR_SOC_P1")
		)
		(pad "2" smd circle
			(at -0.40005 0 90)
			(size 0 0)
			(layers "B.Cu" "B.Mask" "B.Paste")
			(net "GND")
		)
	)
)
